#ISCELL
  mstr_misc dns *
  *
#ISCELL
  pure_quanta quanta_title_block_c *
  *
#ISCELL
  logical_power universal_gnd *
  page274_i1
#ISCELL
  logical_power universal_gnd *
  page274_i10
#CELL
  pure_quanta isl99390frztr5935 *
  page274_i11
#CELL
  pure_quanta q_res *
  page274_i12
#ISCELL
  logical_power vcc15 *
  page274_i13
#ISCELL
  logical_power universal_gnd *
  page274_i14
#CELL
  pure_quanta q_res *
  page274_i15
#ISCELL
  standard offpage *
  page274_i16
#ISCELL
  standard offpage *
  page274_i17
#CELL
  pure_quanta q_cap *
  page274_i18
#ISCELL
  logical_power universal_gnd *
  page274_i19
#ISCELL
  standard offpage *
  page274_i2
#CELL
  pure_quanta isl99390frztr5935 *
  page274_i20
#ISCELL
  logical_power universal_gnd *
  page274_i21
#ISCELL
  logical_power universal_gnd *
  page274_i22
#CELL
  pure_quanta q_inductor *
  page274_i23
#CELL
  pure_quanta q_cap *
  page274_i24
#ISCELL
  logical_power universal_gnd *
  page274_i25
#CELL
  pure_quanta q_res *
  page274_i26
#CELL
  pure_quanta q_cap *
  page274_i27
#CELL
  pure_quanta q_cap *
  page274_i28
#ISCELL
  logical_power universal_gnd *
  page274_i29
#CELL
  pure_quanta q_res *
  page274_i3
#ISCELL
  standard offpage *
  page274_i30
#ISCELL
  standard offpage *
  page274_i31
#CELL
  pure_quanta q_cap *
  page274_i32
#ISCELL
  logical_power universal_gnd *
  page274_i33
#CELL
  pure_quanta q_cap *
  page274_i34
#ISCELL
  logical_power vcc15 *
  page274_i35
#ISCELL
  logical_power universal_gnd *
  page274_i36
#CELL
  pure_quanta q_cap *
  page274_i37
#ISCELL
  standard offpage *
  page274_i38
#CELL
  pure_quanta q_res *
  page274_i39
#ISCELL
  logical_power universal_gnd *
  page274_i4
#CELL
  pure_quanta q_cap *
  page274_i40
#CELL
  pure_quanta q_cap *
  page274_i41
#CELL
  pure_quanta q_cap *
  page274_i42
#CELL
  pure_quanta q_inductor4p_14 *
  page274_i43
#CELL
  pure_quanta q_res *
  page274_i44
#ISCELL
  standard offpage *
  page274_i45
#CELL
  pure_quanta q_cap *
  page274_i46
#CELL
  pure_quanta q_cap *
  page274_i47
#ISCELL
  logical_power universal_gnd *
  page274_i48
#ISCELL
  logical_power vcc15 *
  page274_i49
#ISCELL
  standard offpage *
  page274_i5
#CELL
  pure_quanta q_res *
  page274_i50
#ISCELL
  logical_power universal_gnd *
  page274_i51
#CELL
  pure_quanta q_cap *
  page274_i52
#CELL
  pure_quanta q_cap *
  page274_i53
#CELL
  pure_quanta q_cap *
  page274_i54
#ISCELL
  logical_power universal_gnd *
  page274_i55
#ISCELL
  logical_power vcc15 *
  page274_i56
#ISCELL
  logical_power universal_gnd *
  page274_i57
#CELL
  pure_quanta q_inductor4p_14 *
  page274_i58
#CELL
  pure_quanta q_cap *
  page274_i59
#ISCELL
  standard offpage *
  page274_i6
#ISCELL
  logical_power universal_gnd *
  page274_i60
#CELL
  pure_quanta q_cap *
  page274_i61
#CELL
  pure_quanta q_cap *
  page274_i62
#ISCELL
  logical_power vcc15 *
  page274_i63
#CELL
  pure_quanta q_cap *
  page274_i64
#CELL
  pure_quanta q_cap *
  page274_i65
#CELL
  pure_quanta q_cap *
  page274_i66
#ISCELL
  logical_power vcc15 *
  page274_i67
#CELL
  pure_quanta q_res *
  page274_i68
#CELL
  pure_quanta q_cap *
  page274_i69
#CELL
  pure_quanta q_cap *
  page274_i7
#ISCELL
  standard offpage *
  page274_i8
#CELL
  pure_quanta q_cap *
  page274_i9
